# T6G (Grand Teton) — schematic netlist excerpt (pin names and nets, part order shuffled) for the footprints in the layout excerpt that follows; sources: Cadence DE-HDL packaged netlist, KiCad conversion of 04192023_DAF0TMB3IC0_F0TG_MB_C_brd_V02_OCP.brd

R374  Q_RES  0 5% CHIP  pkg 0402LF  page 57 : A = PVDD18_S5_P1 ; B = CPU1_VDDBT_RTC_G
C923  Q_CAP_DIFFBUS  DIFF BUS_0.22UF 6.3V 20% X6S  pkg C0201  page 63 : \1\ = P5E_CPU0_P0_TX_C_DP<5> ; \2\ = P5E_CPU0_P0_TX_DP<5>
C6020  Q_CAP_DIFFBUS  DIFF BUS_0.33UF 6.3V 10% X6S  pkg C0402  page 180 : \1\ = USB3_CPU0_BMC_RX_DN ; \2\ = USB3_CPU0_BMC_RX_C1_DN

(kicad_pcb
	(version 20260206)
	(generator "pcbnew")
	(generator_version "10.0")
	(general
		(thickness 1.6)
		(legacy_teardrops no)
	)
	(paper "A4")
	(title_block
		(title "04192023_DAF0TMB3IC0_F0TG_MB_C_brd_V02_OCP.brd")
		(comment 1 "Grand Teton / footprints 3613-3615 of 8354")
	)
	(layers
		(0 "F.Cu" signal "TOP")
		(4 "In1.Cu" signal "GND")
		(6 "In2.Cu" signal "IN1")
		(8 "In3.Cu" signal "GND1")
		(10 "In4.Cu" signal "IN2")
		(12 "In5.Cu" signal "GND2")
		(14 "In6.Cu" signal "IN3")
		(16 "In7.Cu" signal "GND3")
		(18 "In8.Cu" signal "VCC")
		(20 "In9.Cu" signal "VCC1")
		(22 "In10.Cu" signal "GND4")
		(24 "In11.Cu" signal "IN4")
		(26 "In12.Cu" signal "GND5")
		(28 "In13.Cu" signal "IN5")
		(30 "In14.Cu" signal "GND6")
		(32 "In15.Cu" signal "IN6")
		(34 "In16.Cu" signal "GND7")
		(2 "B.Cu" signal "BOTTOM")
		(9 "F.Adhes" user "F.Adhesive")
		(11 "B.Adhes" user "B.Adhesive")
		(13 "F.Paste" user "Package Geometry/Pastemask Top")
		(15 "B.Paste" user "Package Geometry/Pastemask Bottom")
		(5 "F.SilkS" user "Ref Des/Silkscreen Top")
		(7 "B.SilkS" user "Ref Des/Silkscreen Bottom")
		(1 "F.Mask" user "Board Geometry/Soldermask Top")
		(3 "B.Mask" user "Board Geometry/Soldermask Bottom")
		(17 "Dwgs.User" user "User.Drawings")
		(19 "Cmts.User" user "User.Comments")
		(21 "Eco1.User" user "User.Eco1")
		(23 "Eco2.User" user "User.Eco2")
		(25 "Edge.Cuts" user "Board Geometry/Outline")
		(27 "Margin" user)
		(31 "F.CrtYd" user "Package Geometry/Place Bound Top")
		(29 "B.CrtYd" user "Package Geometry/Place Bound Bottom")
		(35 "F.Fab" user "Ref Des/Assembly Top")
		(33 "B.Fab" user "Ref Des/Assembly Bottom")
	)
	(footprint ""
		(layer "F.Cu")
		(at 149.649434 -320.717672 180)
		(property "Reference" "R374"
			(at 0 0 180)
			(layer "F.SilkS")
			(hide yes)
			(effects
				(font
					(size 1.27 1.27)
				)
			)
		)
		(property "Value" ""
			(at 0 0 180)
			(layer "F.Fab")
			(effects
				(font
					(size 1.27 1.27)
				)
			)
		)
		(duplicate_pad_numbers_are_jumpers no)
		(fp_line
			(start 0.7874 0.4064)
			(end -0.7874 0.4064)
			(stroke
				(width 0.1524)
				(type default)
			)
			(layer "F.SilkS")
		)
		(fp_line
			(start 0.7874 -0.4064)
			(end 0.7874 0.4064)
			(stroke
				(width 0.1524)
				(type default)
			)
			(layer "F.SilkS")
		)
		(fp_line
			(start -0.7874 0.4064)
			(end -0.7874 -0.4064)
			(stroke
				(width 0.1524)
				(type default)
			)
			(layer "F.SilkS")
		)
		(fp_line
			(start -0.7874 -0.4064)
			(end 0.7874 -0.4064)
			(stroke
				(width 0.1524)
				(type default)
			)
			(layer "F.SilkS")
		)
		(fp_line
			(start 0.67945 0.3048)
			(end 0.120396 0.3048)
			(stroke
				(width 0.1)
				(type default)
			)
			(layer "F.Fab")
		)
		(fp_line
			(start 0.67945 -0.3048)
			(end 0.67945 0.3048)
			(stroke
				(width 0.1)
				(type default)
			)
			(layer "F.Fab")
		)
		(fp_line
			(start 0.12065 -0.2794)
			(end 0.12065 -0.3048)
			(stroke
				(width 0.1)
				(type default)
			)
			(layer "F.Fab")
		)
		(fp_line
			(start 0.12065 -0.3048)
			(end 0.67945 -0.3048)
			(stroke
				(width 0.1)
				(type default)
			)
			(layer "F.Fab")
		)
		(fp_line
			(start 0.120396 0.3048)
			(end 0.120396 0.2794)
			(stroke
				(width 0.1)
				(type default)
			)
			(layer "F.Fab")
		)
		(fp_line
			(start 0.120396 0.2794)
			(end -0.12065 0.2794)
			(stroke
				(width 0.1)
				(type default)
			)
			(layer "F.Fab")
		)
		(fp_line
			(start -0.12065 0.3048)
			(end -0.67945 0.3048)
			(stroke
				(width 0.1)
				(type default)
			)
			(layer "F.Fab")
		)
		(fp_line
			(start -0.12065 0.2794)
			(end -0.12065 0.3048)
			(stroke
				(width 0.1)
				(type default)
			)
			(layer "F.Fab")
		)
		(fp_line
			(start -0.12065 -0.2794)
			(end 0.12065 -0.2794)
			(stroke
				(width 0.1)
				(type default)
			)
			(layer "F.Fab")
		)
		(fp_line
			(start -0.12065 -0.305054)
			(end -0.12065 -0.2794)
			(stroke
				(width 0.1)
				(type default)
			)
			(layer "F.Fab")
		)
		(fp_line
			(start -0.67945 0.3048)
			(end -0.67945 -0.305054)
			(stroke
				(width 0.1)
				(type default)
			)
			(layer "F.Fab")
		)
		(fp_line
			(start -0.67945 -0.305054)
			(end -0.12065 -0.305054)
			(stroke
				(width 0.1)
				(type default)
			)
			(layer "F.Fab")
		)
		(pad "1" smd circle
			(at -0.40005 0 180)
			(size 0 0)
			(layers "F.Cu" "F.Mask" "F.Paste")
			(net "PVDD18_S5_P1")
		)
		(pad "2" smd circle
			(at 0.40005 0 180)
			(size 0 0)
			(layers "F.Cu" "F.Mask" "F.Paste")
			(net "CPU1_VDDBT_RTC_G")
		)
	)
	(footprint ""
		(layer "F.Cu")
		(at 305.796696 -381.41783 -90)
		(property "Reference" "C923"
			(at 0 0 270)
			(layer "F.SilkS")
			(hide yes)
			(effects
				(font
					(size 1.27 1.27)
				)
			)
		)
		(property "Value" ""
			(at 0 0 270)
			(layer "F.Fab")
			(effects
				(font
					(size 1.27 1.27)
				)
			)
		)
		(duplicate_pad_numbers_are_jumpers no)
		(fp_line
			(start -0.299974 0.150114)
			(end -0.299974 -0.150114)
			(stroke
				(width 0.1)
				(type default)
			)
			(layer "F.Fab")
		)
		(fp_line
			(start 0.299974 0.150114)
			(end -0.299974 0.150114)
			(stroke
				(width 0.1)
				(type default)
			)
			(layer "F.Fab")
		)
		(fp_line
			(start -0.299974 -0.150114)
			(end 0.299974 -0.150114)
			(stroke
				(width 0.1)
				(type default)
			)
			(layer "F.Fab")
		)
		(fp_line
			(start 0.299974 -0.150114)
			(end 0.299974 0.150114)
			(stroke
				(width 0.1)
				(type default)
			)
			(layer "F.Fab")
		)
		(pad "1" smd rect
			(at -0.2667 0 270)
			(size 0.3048 0.381)
			(layers "F.Cu" "F.Mask" "F.Paste")
			(net "P5E_CPU0_P0_TX_C_DP<5>")
		)
		(pad "2" smd rect
			(at 0.2667 0 270)
			(size 0.3048 0.381)
			(layers "F.Cu" "F.Mask" "F.Paste")
			(net "P5E_CPU0_P0_TX_DP<5>")
		)
	)
	(footprint ""
		(layer "F.Cu")
		(at 125.38837 -34.021268)
		(property "Reference" "C6020"
			(at 0 0 0)
			(layer "F.SilkS")
			(hide yes)
			(effects
				(font
					(size 1.27 1.27)
				)
			)
		)
		(property "Value" ""
			(at 0 0 0)
			(layer "F.Fab")
			(effects
				(font
					(size 1.27 1.27)
				)
			)
		)
		(duplicate_pad_numbers_are_jumpers no)
		(fp_line
			(start -0.40005 -0.4064)
			(end 0.40005 -0.4064)
			(stroke
				(width 0.1524)
				(type default)
			)
			(layer "F.SilkS")
		)
		(fp_line
			(start 0.40005 0.4064)
			(end -0.40005 0.4064)
			(stroke
				(width 0.1524)
				(type default)
			)
			(layer "F.SilkS")
		)
		(fp_line
			(start -0.6858 -0.3048)
			(end -0.1016 -0.3048)
			(stroke
				(width 0.1)
				(type default)
			)
			(layer "F.Fab")
		)
		(fp_line
			(start -0.6858 0.3048)
			(end -0.6858 -0.3048)
			(stroke
				(width 0.1)
				(type default)
			)
			(layer "F.Fab")
		)
		(fp_line
			(start -0.1016 -0.3048)
			(end -0.1016 -0.2794)
			(stroke
				(width 0.1)
				(type default)
			)
			(layer "F.Fab")
		)
		(fp_line
			(start -0.1016 -0.2794)
			(end 0.1016 -0.2794)
			(stroke
				(width 0.1)
				(type default)
			)
			(layer "F.Fab")
		)
		(fp_line
			(start -0.1016 0.2794)
			(end -0.1016 0.3048)
			(stroke
				(width 0.1)
				(type default)
			)
			(layer "F.Fab")
		)
		(fp_line
			(start -0.1016 0.3048)
			(end -0.6858 0.3048)
			(stroke
				(width 0.1)
				(type default)
			)
			(layer "F.Fab")
		)
		(fp_line
			(start 0.1016 -0.3048)
			(end 0.6858 -0.3048)
			(stroke
				(width 0.1)
				(type default)
			)
			(layer "F.Fab")
		)
		(fp_line
			(start 0.1016 -0.2794)
			(end 0.1016 -0.3048)
			(stroke
				(width 0.1)
				(type default)
			)
			(layer "F.Fab")
		)
		(fp_line
			(start 0.1016 0.2794)
			(end -0.1016 0.2794)
			(stroke
				(width 0.1)
				(type default)
			)
			(layer "F.Fab")
		)
		(fp_line
			(start 0.1016 0.3048)
			(end 0.1016 0.2794)
			(stroke
				(width 0.1)
				(type default)
			)
			(layer "F.Fab")
		)
		(fp_line
			(start 0.6858 -0.3048)
			(end 0.6858 0.3048)
			(stroke
				(width 0.1)
				(type default)
			)
			(layer "F.Fab")
		)
		(fp_line
			(start 0.6858 0.3048)
			(end 0.1016 0.3048)
			(stroke
				(width 0.1)
				(type default)
			)
			(layer "F.Fab")
		)
		(pad "1" smd rect
			(at -0.40005 0 180)
			(size 0.4572 0.508)
			(layers "F.Cu" "F.Mask" "F.Paste")
			(net "USB3_CPU0_BMC_RX_DN")
		)
		(pad "2" smd rect
			(at 0.40005 0 180)
			(size 0.4572 0.508)
			(layers "F.Cu" "F.Mask" "F.Paste")
			(net "USB3_CPU0_BMC_RX_C1_DN")
		)
	)
)
